(kicad_pcb
	(version 20241229)
	(generator "pcbnew")
	(generator_version "9.0")
	(general
		(thickness 1.6296)
		(legacy_teardrops no)
	)
	(paper "A3")
	(title_block
		(title "Thunderbolt to 10GbE adapter")
		(date "2026-04-21")
		(rev "1.1.0")
		(company "Antmicro Ltd")
		(comment 1 "www.antmicro.com")
		(comment 9 "footprints 397-401 of 703")
	)
	(layers
		(0 "F.Cu" signal)
		(4 "In1.Cu" signal)
		(6 "In2.Cu" signal)
		(8 "In3.Cu" signal)
		(10 "In4.Cu" signal)
		(12 "In5.Cu" signal)
		(14 "In6.Cu" signal)
		(2 "B.Cu" signal)
		(9 "F.Adhes" user "F.Adhesive")
		(11 "B.Adhes" user "B.Adhesive")
		(13 "F.Paste" user)
		(15 "B.Paste" user)
		(5 "F.SilkS" user "F.Silkscreen")
		(7 "B.SilkS" user "B.Silkscreen")
		(1 "F.Mask" user)
		(3 "B.Mask" user)
		(17 "Dwgs.User" user "User.Drawings")
		(19 "Cmts.User" user "User.Comments")
		(21 "Eco1.User" user "User.Eco1")
		(23 "Eco2.User" user "User.Eco2")
		(25 "Edge.Cuts" user)
		(27 "Margin" user)
		(31 "F.CrtYd" user "F.Courtyard")
		(29 "B.CrtYd" user "B.Courtyard")
		(35 "F.Fab" user)
		(33 "B.Fab" user)
	)
	(footprint "antmicro-footprints:C_0402_1005Metric"
		(layer "B.Cu")
		(at 147.481866 77.260117 180)
		(descr "Capacitor SMD 0402")
		(tags "capacitor SMD 0402")
		(property "Reference" "C228"
			(at -18.618135 -9.464883 0)
			(layer "B.SilkS")
			(effects
				(font
					(size 0.7 0.7)
					(thickness 0.15)
				)
				(justify mirror)
			)
		)
		(property "Value" "C_1u_25V_0402"
			(at -1.022927 -2.155213 0)
			(layer "B.Fab")
			(effects
				(font
					(size 0.7 0.7)
					(thickness 0.15)
				)
				(justify left bottom mirror)
			)
		)
		(property "Datasheet" "https://www.murata.com/products/productdetail?partno=GRM155R61E105KE11%23"
			(at 0 0 0)
			(layer "B.Fab")
			(hide yes)
			(effects
				(font
					(size 1.27 1.27)
					(thickness 0.15)
				)
				(justify mirror)
			)
		)
		(property "Description" "SMD Multilayer Ceramic Capacitor, 1 µF, 25 V, 0402 [1005 Metric], ± 10%, X5R, GRM Series"
			(at 0 0 0)
			(layer "B.Fab")
			(hide yes)
			(effects
				(font
					(size 1.27 1.27)
					(thickness 0.15)
				)
				(justify mirror)
			)
		)
		(property "MPN" "GRM155R61E105KE11J"
			(at 0 0 180)
			(unlocked yes)
			(layer "B.Fab")
			(hide yes)
			(effects
				(font
					(size 1 1)
					(thickness 0.15)
				)
				(justify mirror)
			)
		)
		(property "Manufacturer" "Murata"
			(at 0 0 180)
			(unlocked yes)
			(layer "B.Fab")
			(hide yes)
			(effects
				(font
					(size 1 1)
					(thickness 0.15)
				)
				(justify mirror)
			)
		)
		(property "License" "Apache-2.0"
			(at 0 0 180)
			(unlocked yes)
			(layer "B.Fab")
			(hide yes)
			(effects
				(font
					(size 1 1)
					(thickness 0.15)
				)
				(justify mirror)
			)
		)
		(property "Author" "Antmicro"
			(at 0 0 180)
			(unlocked yes)
			(layer "B.Fab")
			(hide yes)
			(effects
				(font
					(size 1 1)
					(thickness 0.15)
				)
				(justify mirror)
			)
		)
		(property "Val" "1u"
			(at 0 0 180)
			(unlocked yes)
			(layer "B.Fab")
			(hide yes)
			(effects
				(font
					(size 1 1)
					(thickness 0.15)
				)
				(justify mirror)
			)
		)
		(property "Voltage" "25V"
			(at 0 0 180)
			(unlocked yes)
			(layer "B.Fab")
			(hide yes)
			(effects
				(font
					(size 1 1)
					(thickness 0.15)
				)
				(justify mirror)
			)
		)
		(property "Dielectric" "X5R"
			(at 0 0 180)
			(unlocked yes)
			(layer "B.Fab")
			(hide yes)
			(effects
				(font
					(size 1 1)
					(thickness 0.15)
				)
				(justify mirror)
			)
		)
		(sheetname "/X710-AT2 power/")
		(sheetfile "x710-at2-power.kicad_sch")
		(attr smd)
		(fp_rect
			(start -0.925 0.47)
			(end 0.925 -0.47)
			(stroke
				(width 0.05)
				(type default)
			)
			(fill no)
			(layer "B.CrtYd")
		)
		(fp_line
			(start 0.504 0.25)
			(end 0.504 -0.248)
			(stroke
				(width 0.15)
				(type solid)
			)
			(layer "B.Fab")
		)
		(fp_line
			(start 0.504 -0.248)
			(end -0.494 -0.248)
			(stroke
				(width 0.15)
				(type solid)
			)
			(layer "B.Fab")
		)
		(fp_line
			(start -0.494 0.25)
			(end 0.504 0.25)
			(stroke
				(width 0.15)
				(type solid)
			)
			(layer "B.Fab")
		)
		(fp_line
			(start -0.494 -0.248)
			(end -0.494 0.25)
			(stroke
				(width 0.15)
				(type solid)
			)
			(layer "B.Fab")
		)
		(fp_text user "Author: Antmicro"
			(at -0.939 -3.399 0)
			(layer "B.Fab")
			(effects
				(font
					(size 0.7 0.7)
					(thickness 0.15)
				)
				(justify left bottom mirror)
			)
		)
		(fp_text user "${REFERENCE}"
			(at -0.939 -4.599 0)
			(layer "B.Fab")
			(effects
				(font
					(size 0.7 0.7)
					(thickness 0.15)
				)
				(justify left bottom mirror)
			)
		)
		(fp_text user "License: Apache-2.0"
			(at -0.939 -5.799 0)
			(layer "B.Fab")
			(effects
				(font
					(size 0.7 0.7)
					(thickness 0.15)
				)
				(justify left bottom mirror)
			)
		)
		(pad "1" smd roundrect
			(at -0.48 0 180)
			(size 0.59 0.64)
			(layers "B.Cu" "B.Mask" "B.Paste")
			(roundrect_rratio 0.25)
			(net 23 "GND")
			(pintype "passive")
		)
		(pad "2" smd roundrect
			(at 0.48 0 180)
			(size 0.59 0.64)
			(layers "B.Cu" "B.Mask" "B.Paste")
			(roundrect_rratio 0.25)
			(net 9 "VCCD")
			(pintype "passive")
		)
	)
	(footprint "antmicro-footprints:C_0402_1005Metric"
		(layer "B.Cu")
		(at 151.181866 78.260117 180)
		(descr "Capacitor SMD 0402")
		(tags "capacitor SMD 0402")
		(property "Reference" "C232"
			(at -20.368136 -9.464883 0)
			(layer "B.SilkS")
			(effects
				(font
					(size 0.7 0.7)
					(thickness 0.15)
				)
				(justify mirror)
			)
		)
		(property "Value" "C_1u_25V_0402"
			(at -1.022927 -2.155213 0)
			(layer "B.Fab")
			(effects
				(font
					(size 0.7 0.7)
					(thickness 0.15)
				)
				(justify left bottom mirror)
			)
		)
		(property "Datasheet" "https://www.murata.com/products/productdetail?partno=GRM155R61E105KE11%23"
			(at 0 0 0)
			(layer "B.Fab")
			(hide yes)
			(effects
				(font
					(size 1.27 1.27)
					(thickness 0.15)
				)
				(justify mirror)
			)
		)
		(property "Description" "SMD Multilayer Ceramic Capacitor, 1 µF, 25 V, 0402 [1005 Metric], ± 10%, X5R, GRM Series"
			(at 0 0 0)
			(layer "B.Fab")
			(hide yes)
			(effects
				(font
					(size 1.27 1.27)
					(thickness 0.15)
				)
				(justify mirror)
			)
		)
		(property "MPN" "GRM155R61E105KE11J"
			(at 0 0 180)
			(unlocked yes)
			(layer "B.Fab")
			(hide yes)
			(effects
				(font
					(size 1 1)
					(thickness 0.15)
				)
				(justify mirror)
			)
		)
		(property "Manufacturer" "Murata"
			(at 0 0 180)
			(unlocked yes)
			(layer "B.Fab")
			(hide yes)
			(effects
				(font
					(size 1 1)
					(thickness 0.15)
				)
				(justify mirror)
			)
		)
		(property "License" "Apache-2.0"
			(at 0 0 180)
			(unlocked yes)
			(layer "B.Fab")
			(hide yes)
			(effects
				(font
					(size 1 1)
					(thickness 0.15)
				)
				(justify mirror)
			)
		)
		(property "Author" "Antmicro"
			(at 0 0 180)
			(unlocked yes)
			(layer "B.Fab")
			(hide yes)
			(effects
				(font
					(size 1 1)
					(thickness 0.15)
				)
				(justify mirror)
			)
		)
		(property "Val" "1u"
			(at 0 0 180)
			(unlocked yes)
			(layer "B.Fab")
			(hide yes)
			(effects
				(font
					(size 1 1)
					(thickness 0.15)
				)
				(justify mirror)
			)
		)
		(property "Voltage" "25V"
			(at 0 0 180)
			(unlocked yes)
			(layer "B.Fab")
			(hide yes)
			(effects
				(font
					(size 1 1)
					(thickness 0.15)
				)
				(justify mirror)
			)
		)
		(property "Dielectric" "X5R"
			(at 0 0 180)
			(unlocked yes)
			(layer "B.Fab")
			(hide yes)
			(effects
				(font
					(size 1 1)
					(thickness 0.15)
				)
				(justify mirror)
			)
		)
		(sheetname "/X710-AT2 power/")
		(sheetfile "x710-at2-power.kicad_sch")
		(attr smd)
		(fp_rect
			(start -0.925 0.47)
			(end 0.925 -0.47)
			(stroke
				(width 0.05)
				(type default)
			)
			(fill no)
			(layer "B.CrtYd")
		)
		(fp_line
			(start 0.504 0.25)
			(end 0.504 -0.248)
			(stroke
				(width 0.15)
				(type solid)
			)
			(layer "B.Fab")
		)
		(fp_line
			(start 0.504 -0.248)
			(end -0.494 -0.248)
			(stroke
				(width 0.15)
				(type solid)
			)
			(layer "B.Fab")
		)
		(fp_line
			(start -0.494 0.25)
			(end 0.504 0.25)
			(stroke
				(width 0.15)
				(type solid)
			)
			(layer "B.Fab")
		)
		(fp_line
			(start -0.494 -0.248)
			(end -0.494 0.25)
			(stroke
				(width 0.15)
				(type solid)
			)
			(layer "B.Fab")
		)
		(fp_text user "${REFERENCE}"
			(at -0.939 -4.599 0)
			(layer "B.Fab")
			(effects
				(font
					(size 0.7 0.7)
					(thickness 0.15)
				)
				(justify left bottom mirror)
			)
		)
		(fp_text user "Author: Antmicro"
			(at -0.939 -3.399 0)
			(layer "B.Fab")
			(effects
				(font
					(size 0.7 0.7)
					(thickness 0.15)
				)
				(justify left bottom mirror)
			)
		)
		(fp_text user "License: Apache-2.0"
			(at -0.939 -5.799 0)
			(layer "B.Fab")
			(effects
				(font
					(size 0.7 0.7)
					(thickness 0.15)
				)
				(justify left bottom mirror)
			)
		)
		(pad "1" smd roundrect
			(at -0.48 0 180)
			(size 0.59 0.64)
			(layers "B.Cu" "B.Mask" "B.Paste")
			(roundrect_rratio 0.25)
			(net 23 "GND")
			(pintype "passive")
		)
		(pad "2" smd roundrect
			(at 0.48 0 180)
			(size 0.59 0.64)
			(layers "B.Cu" "B.Mask" "B.Paste")
			(roundrect_rratio 0.25)
			(net 1 "VCCA")
			(pintype "passive")
		)
	)
	(footprint "antmicro-footprints:R_0402_1005Metric"
		(layer "B.Cu")
		(at 136.75 140.9 -90)
		(descr "Resistor SMD 0402")
		(tags "resistor SMD 0402")
		(property "Reference" "R28"
			(at -9.557574 -19.525001 90)
			(layer "B.SilkS")
			(effects
				(font
					(size 0.7 0.7)
					(thickness 0.15)
				)
				(justify mirror)
			)
		)
		(property "Value" "R_100k_0402"
			(at -1.011843 -1.772047 90)
			(layer "B.Fab")
			(effects
				(font
					(size 0.7 0.7)
					(thickness 0.15)
				)
				(justify left bottom mirror)
			)
		)
		(property "Datasheet" "https://www.bourns.com/docs/product-datasheets/cr.pdf"
			(at 0 0 90)
			(layer "B.Fab")
			(hide yes)
			(effects
				(font
					(size 1.27 1.27)
					(thickness 0.15)
				)
				(justify mirror)
			)
		)
		(property "Description" "SMD Chip Resistor, 100 kohm, ± 1%, 62.5 mW, 0402 [1005 Metric], Thick Film, General Purpose"
			(at 0 0 90)
			(layer "B.Fab")
			(hide yes)
			(effects
				(font
					(size 1.27 1.27)
					(thickness 0.15)
				)
				(justify mirror)
			)
		)
		(property "MPN" "CR0402-FX-1003GLF"
			(at 0 0 270)
			(unlocked yes)
			(layer "B.Fab")
			(hide yes)
			(effects
				(font
					(size 1 1)
					(thickness 0.15)
				)
				(justify mirror)
			)
		)
		(property "Manufacturer" "Bourns"
			(at 0 0 270)
			(unlocked yes)
			(layer "B.Fab")
			(hide yes)
			(effects
				(font
					(size 1 1)
					(thickness 0.15)
				)
				(justify mirror)
			)
		)
		(property "License" "Apache-2.0"
			(at 0 0 270)
			(unlocked yes)
			(layer "B.Fab")
			(hide yes)
			(effects
				(font
					(size 1 1)
					(thickness 0.15)
				)
				(justify mirror)
			)
		)
		(property "Val" "100k"
			(at 0 0 270)
			(unlocked yes)
			(layer "B.Fab")
			(hide yes)
			(effects
				(font
					(size 1 1)
					(thickness 0.15)
				)
				(justify mirror)
			)
		)
		(property "Tolerance" "1%"
			(at 0 0 270)
			(unlocked yes)
			(layer "B.Fab")
			(hide yes)
			(effects
				(font
					(size 1 1)
					(thickness 0.15)
				)
				(justify mirror)
			)
		)
		(property "Author" "Antmicro"
			(at 0 0 270)
			(unlocked yes)
			(layer "B.Fab")
			(hide yes)
			(effects
				(font
					(size 1 1)
					(thickness 0.15)
				)
				(justify mirror)
			)
		)
		(sheetname "/PD and TB DC-DC/")
		(sheetfile "PD_and_TB_DC_DC.kicad_sch")
		(attr smd)
		(fp_rect
			(start -0.925 0.47)
			(end 0.925 -0.47)
			(stroke
				(width 0.05)
				(type default)
			)
			(fill no)
			(layer "B.CrtYd")
		)
		(fp_rect
			(start -0.5 0.25)
			(end 0.5 -0.25)
			(stroke
				(width 0.15)
				(type solid)
			)
			(fill no)
			(layer "B.Fab")
		)
		(fp_text user "Author: Antmicro"
			(at -0.95 -4.169 90)
			(layer "B.Fab")
			(effects
				(font
					(size 0.7 0.7)
					(thickness 0.15)
				)
				(justify left bottom mirror)
			)
		)
		(fp_text user "${REFERENCE}"
			(at -0.95 -3.168 90)
			(layer "B.Fab")
			(effects
				(font
					(size 0.7 0.7)
					(thickness 0.15)
				)
				(justify left bottom mirror)
			)
		)
		(fp_text user "License: Apache-2.0"
			(at -0.95 -5.169 90)
			(layer "B.Fab")
			(effects
				(font
					(size 0.7 0.7)
					(thickness 0.15)
				)
				(justify left bottom mirror)
			)
		)
		(pad "1" smd roundrect
			(at -0.48 0 270)
			(size 0.59 0.64)
			(layers "B.Cu" "B.Mask" "B.Paste")
			(roundrect_rratio 0.25)
			(net 211 "Net-(U3-BUSPOWERZ(GPIO10))")
			(pintype "passive")
		)
		(pad "2" smd roundrect
			(at 0.48 0 270)
			(size 0.59 0.64)
			(layers "B.Cu" "B.Mask" "B.Paste")
			(roundrect_rratio 0.25)
			(net 304 "/PD and TB DC-DC/TPS_3V3")
			(pintype "passive")
		)
	)
	(footprint "antmicro-footprints:R_0402_1005Metric"
		(layer "B.Cu")
		(at 139.199999 133.600001 180)
		(descr "Resistor SMD 0402")
		(tags "resistor SMD 0402")
		(property "Reference" "R8"
			(at -19.525001 8.1 0)
			(layer "B.SilkS")
			(effects
				(font
					(size 0.7 0.7)
					(thickness 0.15)
				)
				(justify mirror)
			)
		)
		(property "Value" "R_10k_0402"
			(at -1.011843 -1.772047 0)
			(layer "B.Fab")
			(effects
				(font
					(size 0.7 0.7)
					(thickness 0.15)
				)
				(justify left bottom mirror)
			)
		)
		(property "Datasheet" "https://www.bourns.com/docs/product-datasheets/cr.pdf"
			(at 0 0 0)
			(layer "B.Fab")
			(hide yes)
			(effects
				(font
					(size 1.27 1.27)
					(thickness 0.15)
				)
				(justify mirror)
			)
		)
		(property "Description" "SMD Chip Resistor, 10 kohm, ± 1%, 62.5 mW, 0402 [1005 Metric], Thick Film, General Purpose"
			(at 0 0 0)
			(layer "B.Fab")
			(hide yes)
			(effects
				(font
					(size 1.27 1.27)
					(thickness 0.15)
				)
				(justify mirror)
			)
		)
		(property "MPN" "CR0402-FX-1002GLF"
			(at 0 0 180)
			(unlocked yes)
			(layer "B.Fab")
			(hide yes)
			(effects
				(font
					(size 1 1)
					(thickness 0.15)
				)
				(justify mirror)
			)
		)
		(property "Manufacturer" "Bourns"
			(at 0 0 180)
			(unlocked yes)
			(layer "B.Fab")
			(hide yes)
			(effects
				(font
					(size 1 1)
					(thickness 0.15)
				)
				(justify mirror)
			)
		)
		(property "License" "Apache-2.0"
			(at 0 0 180)
			(unlocked yes)
			(layer "B.Fab")
			(hide yes)
			(effects
				(font
					(size 1 1)
					(thickness 0.15)
				)
				(justify mirror)
			)
		)
		(property "Val" "10k"
			(at 0 0 180)
			(unlocked yes)
			(layer "B.Fab")
			(hide yes)
			(effects
				(font
					(size 1 1)
					(thickness 0.15)
				)
				(justify mirror)
			)
		)
		(property "Tolerance" "1%"
			(at 0 0 180)
			(unlocked yes)
			(layer "B.Fab")
			(hide yes)
			(effects
				(font
					(size 1 1)
					(thickness 0.15)
				)
				(justify mirror)
			)
		)
		(property "Author" "Antmicro"
			(at 0 0 180)
			(unlocked yes)
			(layer "B.Fab")
			(hide yes)
			(effects
				(font
					(size 1 1)
					(thickness 0.15)
				)
				(justify mirror)
			)
		)
		(sheetname "/PD and TB DC-DC/")
		(sheetfile "PD_and_TB_DC_DC.kicad_sch")
		(attr smd)
		(fp_rect
			(start -0.925 0.47)
			(end 0.925 -0.47)
			(stroke
				(width 0.05)
				(type default)
			)
			(fill no)
			(layer "B.CrtYd")
		)
		(fp_rect
			(start -0.5 0.25)
			(end 0.5 -0.25)
			(stroke
				(width 0.15)
				(type solid)
			)
			(fill no)
			(layer "B.Fab")
		)
		(fp_text user "License: Apache-2.0"
			(at -0.95 -5.169 0)
			(layer "B.Fab")
			(effects
				(font
					(size 0.7 0.7)
					(thickness 0.15)
				)
				(justify left bottom mirror)
			)
		)
		(fp_text user "Author: Antmicro"
			(at -0.95 -4.169 0)
			(layer "B.Fab")
			(effects
				(font
					(size 0.7 0.7)
					(thickness 0.15)
				)
				(justify left bottom mirror)
			)
		)
		(fp_text user "${REFERENCE}"
			(at -0.95 -3.168 0)
			(layer "B.Fab")
			(effects
				(font
					(size 0.7 0.7)
					(thickness 0.15)
				)
				(justify left bottom mirror)
			)
		)
		(pad "1" smd roundrect
			(at -0.48 0 180)
			(size 0.59 0.64)
			(layers "B.Cu" "B.Mask" "B.Paste")
			(roundrect_rratio 0.25)
			(net 372 "/PD and TB DC-DC/I2C1.IRQ")
			(pintype "passive")
		)
		(pad "2" smd roundrect
			(at 0.48 0 180)
			(size 0.59 0.64)
			(layers "B.Cu" "B.Mask" "B.Paste")
			(roundrect_rratio 0.25)
			(net 57 "+3V3_TB")
			(pintype "passive")
		)
	)
	(footprint "antmicro-footprints:TP_SMD_0.75mm"
		(layer "B.Cu")
		(at 152.2 62.935117 -90)
		(property "Reference" "TP25"
			(at -3.135117 -0.2 90)
			(layer "B.SilkS")
			(effects
				(font
					(size 0.7 0.7)
					(thickness 0.15)
				)
				(justify left bottom mirror)
			)
		)
		(property "Value" "TP_0.75mm_SMD"
			(at 0 -1.2 90)
			(layer "B.Fab")
			(effects
				(font
					(size 0.7 0.7)
					(thickness 0.15)
				)
				(justify left bottom mirror)
			)
		)
		(property "Description" "SMT test point"
			(at 0 0 90)
			(layer "B.Fab")
			(hide yes)
			(effects
				(font
					(size 1.27 1.27)
					(thickness 0.15)
				)
				(justify mirror)
			)
		)
		(property "MPN" ""
			(at 0 0 270)
			(unlocked yes)
			(layer "B.Fab")
			(hide yes)
			(effects
				(font
					(size 1 1)
					(thickness 0.15)
				)
				(justify mirror)
			)
		)
		(property "Manufacturer" ""
			(at 0 0 270)
			(unlocked yes)
			(layer "B.Fab")
			(hide yes)
			(effects
				(font
					(size 1 1)
					(thickness 0.15)
				)
				(justify mirror)
			)
		)
		(property "Author" "Antmicro"
			(at 0 0 270)
			(unlocked yes)
			(layer "B.Fab")
			(hide yes)
			(effects
				(font
					(size 1 1)
					(thickness 0.15)
				)
				(justify mirror)
			)
		)
		(property "License" "Apache-2.0"
			(at 0 0 270)
			(unlocked yes)
			(layer "B.Fab")
			(hide yes)
			(effects
				(font
					(size 1 1)
					(thickness 0.15)
				)
				(justify mirror)
			)
		)
		(sheetname "/X710-AT2 Misc/")
		(sheetfile "x710-at2-mics.kicad_sch")
		(attr exclude_from_pos_files exclude_from_bom)
		(fp_circle
			(center 0 0)
			(end 0.475 0)
			(stroke
				(width 0.05)
				(type default)
			)
			(fill no)
			(layer "B.CrtYd")
		)
		(fp_text user "License: Apache-2.0"
			(at -0.4 -5.101 90)
			(layer "B.Fab")
			(effects
				(font
					(size 0.7 0.7)
					(thickness 0.15)
				)
				(justify left bottom mirror)
			)
		)
		(fp_text user "${REFERENCE}"
			(at -0.4 -2.7 90)
			(layer "B.Fab")
			(effects
				(font
					(size 0.7 0.7)
					(thickness 0.15)
				)
				(justify left bottom mirror)
			)
		)
		(fp_text user "Author: Antmicro"
			(at -0.4 -3.901 90)
			(layer "B.Fab")
			(effects
				(font
					(size 0.7 0.7)
					(thickness 0.15)
				)
				(justify left bottom mirror)
			)
		)
		(pad "1" smd circle
			(at 0 0 270)
			(size 0.75 0.75)
			(layers "B.Cu" "B.Mask")
			(net 143 "/X710-AT2 Misc/NCSI.TX_EN")
			(pinfunction "1")
			(pintype "passive")
		)
	)
)
